(kicad_pcb
	(version 20260206)
	(generator "pcbnew")
	(generator_version "10.0")
	(general
		(thickness 1.6)
		(legacy_teardrops no)
	)
	(paper "A4")
	(title_block
		(title "03242023_DA0F0TMBIJ0_F0T_Motherboard_J_brd_V01_OCP.brd")
		(comment 1 "Grand Teton / footprints 3124-3129 of 6105")
	)
	(layers
		(0 "F.Cu" signal "TOP")
		(4 "In1.Cu" signal "GND")
		(6 "In2.Cu" signal "IN1")
		(8 "In3.Cu" signal "GND1")
		(10 "In4.Cu" signal "IN2")
		(12 "In5.Cu" signal "GND2")
		(14 "In6.Cu" signal "IN3")
		(16 "In7.Cu" signal "GND3")
		(18 "In8.Cu" signal "VCC")
		(20 "In9.Cu" signal "VCC1")
		(22 "In10.Cu" signal "GND4")
		(24 "In11.Cu" signal "IN4")
		(26 "In12.Cu" signal "GND5")
		(28 "In13.Cu" signal "IN5")
		(30 "In14.Cu" signal "GND6")
		(32 "In15.Cu" signal "IN6")
		(34 "In16.Cu" signal "GND7")
		(2 "B.Cu" signal "BOTTOM")
		(9 "F.Adhes" user "F.Adhesive")
		(11 "B.Adhes" user "B.Adhesive")
		(13 "F.Paste" user "Package Geometry/Pastemask Top")
		(15 "B.Paste" user "Package Geometry/Pastemask Bottom")
		(5 "F.SilkS" user "Ref Des/Silkscreen Top")
		(7 "B.SilkS" user "Ref Des/Silkscreen Bottom")
		(1 "F.Mask" user "Board Geometry/Soldermask Top")
		(3 "B.Mask" user "Board Geometry/Soldermask Bottom")
		(17 "Dwgs.User" user "User.Drawings")
		(19 "Cmts.User" user "User.Comments")
		(21 "Eco1.User" user "User.Eco1")
		(23 "Eco2.User" user "User.Eco2")
		(25 "Edge.Cuts" user "Board Geometry/Outline")
		(27 "Margin" user)
		(31 "F.CrtYd" user "Package Geometry/Place Bound Top")
		(29 "B.CrtYd" user "Package Geometry/Place Bound Bottom")
		(35 "F.Fab" user "Ref Des/Assembly Top")
		(33 "B.Fab" user "Ref Des/Assembly Bottom")
	)
	(footprint ""
		(layer "F.Cu")
		(at 15.436596 -393.215876 180)
		(property "Reference" "R3276"
			(at 0 0 180)
			(layer "F.SilkS")
			(hide yes)
			(effects
				(font
					(size 1.27 1.27)
				)
			)
		)
		(property "Value" ""
			(at 0 0 180)
			(layer "F.Fab")
			(effects
				(font
					(size 1.27 1.27)
				)
			)
		)
		(duplicate_pad_numbers_are_jumpers no)
		(fp_line
			(start 0.7874 0.4064)
			(end -0.7874 0.4064)
			(stroke
				(width 0.1524)
				(type default)
			)
			(layer "F.SilkS")
		)
		(fp_line
			(start 0.7874 -0.4064)
			(end 0.7874 0.4064)
			(stroke
				(width 0.1524)
				(type default)
			)
			(layer "F.SilkS")
		)
		(fp_line
			(start -0.7874 0.4064)
			(end -0.7874 -0.4064)
			(stroke
				(width 0.1524)
				(type default)
			)
			(layer "F.SilkS")
		)
		(fp_line
			(start -0.7874 -0.4064)
			(end 0.7874 -0.4064)
			(stroke
				(width 0.1524)
				(type default)
			)
			(layer "F.SilkS")
		)
		(fp_line
			(start 0.67945 0.3048)
			(end 0.120396 0.3048)
			(stroke
				(width 0.1)
				(type default)
			)
			(layer "F.Fab")
		)
		(fp_line
			(start 0.67945 -0.3048)
			(end 0.67945 0.3048)
			(stroke
				(width 0.1)
				(type default)
			)
			(layer "F.Fab")
		)
		(fp_line
			(start 0.12065 -0.2794)
			(end 0.12065 -0.3048)
			(stroke
				(width 0.1)
				(type default)
			)
			(layer "F.Fab")
		)
		(fp_line
			(start 0.12065 -0.3048)
			(end 0.67945 -0.3048)
			(stroke
				(width 0.1)
				(type default)
			)
			(layer "F.Fab")
		)
		(fp_line
			(start 0.120396 0.3048)
			(end 0.120396 0.2794)
			(stroke
				(width 0.1)
				(type default)
			)
			(layer "F.Fab")
		)
		(fp_line
			(start 0.120396 0.2794)
			(end -0.12065 0.2794)
			(stroke
				(width 0.1)
				(type default)
			)
			(layer "F.Fab")
		)
		(fp_line
			(start -0.12065 0.3048)
			(end -0.67945 0.3048)
			(stroke
				(width 0.1)
				(type default)
			)
			(layer "F.Fab")
		)
		(fp_line
			(start -0.12065 0.2794)
			(end -0.12065 0.3048)
			(stroke
				(width 0.1)
				(type default)
			)
			(layer "F.Fab")
		)
		(fp_line
			(start -0.12065 -0.2794)
			(end 0.12065 -0.2794)
			(stroke
				(width 0.1)
				(type default)
			)
			(layer "F.Fab")
		)
		(fp_line
			(start -0.12065 -0.305054)
			(end -0.12065 -0.2794)
			(stroke
				(width 0.1)
				(type default)
			)
			(layer "F.Fab")
		)
		(fp_line
			(start -0.67945 0.3048)
			(end -0.67945 -0.305054)
			(stroke
				(width 0.1)
				(type default)
			)
			(layer "F.Fab")
		)
		(fp_line
			(start -0.67945 -0.305054)
			(end -0.12065 -0.305054)
			(stroke
				(width 0.1)
				(type default)
			)
			(layer "F.Fab")
		)
		(pad "1" smd circle
			(at -0.40005 0 180)
			(size 0 0)
			(layers "F.Cu" "F.Mask" "F.Paste")
			(net "FM_P2E_FGA")
		)
		(pad "2" smd circle
			(at 0.40005 0 180)
			(size 0 0)
			(layers "F.Cu" "F.Mask" "F.Paste")
			(net "GND")
		)
	)
	(footprint ""
		(layer "F.Cu")
		(at 431.989992 -391.505948 180)
		(property "Reference" "R2836"
			(at 0 0 180)
			(layer "F.SilkS")
			(hide yes)
			(effects
				(font
					(size 1.27 1.27)
				)
			)
		)
		(property "Value" ""
			(at 0 0 180)
			(layer "F.Fab")
			(effects
				(font
					(size 1.27 1.27)
				)
			)
		)
		(duplicate_pad_numbers_are_jumpers no)
		(fp_line
			(start 0.7874 0.4064)
			(end -0.7874 0.4064)
			(stroke
				(width 0.1524)
				(type default)
			)
			(layer "F.SilkS")
		)
		(fp_line
			(start 0.7874 -0.4064)
			(end 0.7874 0.4064)
			(stroke
				(width 0.1524)
				(type default)
			)
			(layer "F.SilkS")
		)
		(fp_line
			(start -0.7874 0.4064)
			(end -0.7874 -0.4064)
			(stroke
				(width 0.1524)
				(type default)
			)
			(layer "F.SilkS")
		)
		(fp_line
			(start -0.7874 -0.4064)
			(end 0.7874 -0.4064)
			(stroke
				(width 0.1524)
				(type default)
			)
			(layer "F.SilkS")
		)
		(fp_line
			(start 0.67945 0.3048)
			(end 0.120396 0.3048)
			(stroke
				(width 0.1)
				(type default)
			)
			(layer "F.Fab")
		)
		(fp_line
			(start 0.67945 -0.3048)
			(end 0.67945 0.3048)
			(stroke
				(width 0.1)
				(type default)
			)
			(layer "F.Fab")
		)
		(fp_line
			(start 0.12065 -0.2794)
			(end 0.12065 -0.3048)
			(stroke
				(width 0.1)
				(type default)
			)
			(layer "F.Fab")
		)
		(fp_line
			(start 0.12065 -0.3048)
			(end 0.67945 -0.3048)
			(stroke
				(width 0.1)
				(type default)
			)
			(layer "F.Fab")
		)
		(fp_line
			(start 0.120396 0.3048)
			(end 0.120396 0.2794)
			(stroke
				(width 0.1)
				(type default)
			)
			(layer "F.Fab")
		)
		(fp_line
			(start 0.120396 0.2794)
			(end -0.12065 0.2794)
			(stroke
				(width 0.1)
				(type default)
			)
			(layer "F.Fab")
		)
		(fp_line
			(start -0.12065 0.3048)
			(end -0.67945 0.3048)
			(stroke
				(width 0.1)
				(type default)
			)
			(layer "F.Fab")
		)
		(fp_line
			(start -0.12065 0.2794)
			(end -0.12065 0.3048)
			(stroke
				(width 0.1)
				(type default)
			)
			(layer "F.Fab")
		)
		(fp_line
			(start -0.12065 -0.2794)
			(end 0.12065 -0.2794)
			(stroke
				(width 0.1)
				(type default)
			)
			(layer "F.Fab")
		)
		(fp_line
			(start -0.12065 -0.305054)
			(end -0.12065 -0.2794)
			(stroke
				(width 0.1)
				(type default)
			)
			(layer "F.Fab")
		)
		(fp_line
			(start -0.67945 0.3048)
			(end -0.67945 -0.305054)
			(stroke
				(width 0.1)
				(type default)
			)
			(layer "F.Fab")
		)
		(fp_line
			(start -0.67945 -0.305054)
			(end -0.12065 -0.305054)
			(stroke
				(width 0.1)
				(type default)
			)
			(layer "F.Fab")
		)
		(pad "1" smd circle
			(at -0.40005 0 180)
			(size 0 0)
			(layers "F.Cu" "F.Mask" "F.Paste")
			(net "P3V3_AUX")
		)
		(pad "2" smd circle
			(at 0.40005 0 180)
			(size 0 0)
			(layers "F.Cu" "F.Mask" "F.Paste")
			(net "FM_SWB_BIC_READY")
		)
	)
	(footprint ""
		(layer "F.Cu")
		(at 315.110622 -55.235348 180)
		(property "Reference" "R1497"
			(at 0 0 180)
			(layer "F.SilkS")
			(hide yes)
			(effects
				(font
					(size 1.27 1.27)
				)
			)
		)
		(property "Value" ""
			(at 0 0 180)
			(layer "F.Fab")
			(effects
				(font
					(size 1.27 1.27)
				)
			)
		)
		(duplicate_pad_numbers_are_jumpers no)
		(fp_line
			(start 0.7874 0.4064)
			(end -0.7874 0.4064)
			(stroke
				(width 0.1524)
				(type default)
			)
			(layer "F.SilkS")
		)
		(fp_line
			(start 0.7874 -0.4064)
			(end 0.7874 0.4064)
			(stroke
				(width 0.1524)
				(type default)
			)
			(layer "F.SilkS")
		)
		(fp_line
			(start -0.7874 0.4064)
			(end -0.7874 -0.4064)
			(stroke
				(width 0.1524)
				(type default)
			)
			(layer "F.SilkS")
		)
		(fp_line
			(start -0.7874 -0.4064)
			(end 0.7874 -0.4064)
			(stroke
				(width 0.1524)
				(type default)
			)
			(layer "F.SilkS")
		)
		(fp_line
			(start 0.67945 0.3048)
			(end 0.120396 0.3048)
			(stroke
				(width 0.1)
				(type default)
			)
			(layer "F.Fab")
		)
		(fp_line
			(start 0.67945 -0.3048)
			(end 0.67945 0.3048)
			(stroke
				(width 0.1)
				(type default)
			)
			(layer "F.Fab")
		)
		(fp_line
			(start 0.12065 -0.2794)
			(end 0.12065 -0.3048)
			(stroke
				(width 0.1)
				(type default)
			)
			(layer "F.Fab")
		)
		(fp_line
			(start 0.12065 -0.3048)
			(end 0.67945 -0.3048)
			(stroke
				(width 0.1)
				(type default)
			)
			(layer "F.Fab")
		)
		(fp_line
			(start 0.120396 0.3048)
			(end 0.120396 0.2794)
			(stroke
				(width 0.1)
				(type default)
			)
			(layer "F.Fab")
		)
		(fp_line
			(start 0.120396 0.2794)
			(end -0.12065 0.2794)
			(stroke
				(width 0.1)
				(type default)
			)
			(layer "F.Fab")
		)
		(fp_line
			(start -0.12065 0.3048)
			(end -0.67945 0.3048)
			(stroke
				(width 0.1)
				(type default)
			)
			(layer "F.Fab")
		)
		(fp_line
			(start -0.12065 0.2794)
			(end -0.12065 0.3048)
			(stroke
				(width 0.1)
				(type default)
			)
			(layer "F.Fab")
		)
		(fp_line
			(start -0.12065 -0.2794)
			(end 0.12065 -0.2794)
			(stroke
				(width 0.1)
				(type default)
			)
			(layer "F.Fab")
		)
		(fp_line
			(start -0.12065 -0.305054)
			(end -0.12065 -0.2794)
			(stroke
				(width 0.1)
				(type default)
			)
			(layer "F.Fab")
		)
		(fp_line
			(start -0.67945 0.3048)
			(end -0.67945 -0.305054)
			(stroke
				(width 0.1)
				(type default)
			)
			(layer "F.Fab")
		)
		(fp_line
			(start -0.67945 -0.305054)
			(end -0.12065 -0.305054)
			(stroke
				(width 0.1)
				(type default)
			)
			(layer "F.Fab")
		)
		(pad "1" smd circle
			(at -0.40005 0 180)
			(size 0 0)
			(layers "F.Cu" "F.Mask" "F.Paste")
			(net "FM_PCH_DFXTESTMODE")
		)
		(pad "2" smd circle
			(at 0.40005 0 180)
			(size 0 0)
			(layers "F.Cu" "F.Mask" "F.Paste")
			(net "GND")
		)
	)
	(footprint ""
		(layer "F.Cu")
		(at 463.82305 -382.610614 90)
		(property "Reference" "PC1648"
			(at 0 0 90)
			(layer "F.SilkS")
			(hide yes)
			(effects
				(font
					(size 1.27 1.27)
				)
			)
		)
		(property "Value" ""
			(at 0 0 90)
			(layer "F.Fab")
			(effects
				(font
					(size 1.27 1.27)
				)
			)
		)
		(duplicate_pad_numbers_are_jumpers no)
		(fp_line
			(start 0.7874 -0.4064)
			(end 0.7874 0.4064)
			(stroke
				(width 0.1524)
				(type default)
			)
			(layer "F.SilkS")
		)
		(fp_line
			(start -0.7874 -0.4064)
			(end 0.7874 -0.4064)
			(stroke
				(width 0.1524)
				(type default)
			)
			(layer "F.SilkS")
		)
		(fp_line
			(start 0.7874 0.4064)
			(end -0.7874 0.4064)
			(stroke
				(width 0.1524)
				(type default)
			)
			(layer "F.SilkS")
		)
		(fp_line
			(start -0.7874 0.4064)
			(end -0.7874 -0.4064)
			(stroke
				(width 0.1524)
				(type default)
			)
			(layer "F.SilkS")
		)
		(fp_line
			(start -0.12065 -0.305054)
			(end -0.12065 -0.2794)
			(stroke
				(width 0.1)
				(type default)
			)
			(layer "F.Fab")
		)
		(fp_line
			(start -0.67945 -0.305054)
			(end -0.12065 -0.305054)
			(stroke
				(width 0.1)
				(type default)
			)
			(layer "F.Fab")
		)
		(fp_line
			(start 0.67945 -0.3048)
			(end 0.67945 0.3048)
			(stroke
				(width 0.1)
				(type default)
			)
			(layer "F.Fab")
		)
		(fp_line
			(start 0.12065 -0.3048)
			(end 0.67945 -0.3048)
			(stroke
				(width 0.1)
				(type default)
			)
			(layer "F.Fab")
		)
		(fp_line
			(start 0.12065 -0.2794)
			(end 0.12065 -0.3048)
			(stroke
				(width 0.1)
				(type default)
			)
			(layer "F.Fab")
		)
		(fp_line
			(start -0.12065 -0.2794)
			(end 0.12065 -0.2794)
			(stroke
				(width 0.1)
				(type default)
			)
			(layer "F.Fab")
		)
		(fp_line
			(start 0.120396 0.2794)
			(end -0.12065 0.2794)
			(stroke
				(width 0.1)
				(type default)
			)
			(layer "F.Fab")
		)
		(fp_line
			(start -0.12065 0.2794)
			(end -0.12065 0.3048)
			(stroke
				(width 0.1)
				(type default)
			)
			(layer "F.Fab")
		)
		(fp_line
			(start 0.67945 0.3048)
			(end 0.120396 0.3048)
			(stroke
				(width 0.1)
				(type default)
			)
			(layer "F.Fab")
		)
		(fp_line
			(start 0.120396 0.3048)
			(end 0.120396 0.2794)
			(stroke
				(width 0.1)
				(type default)
			)
			(layer "F.Fab")
		)
		(fp_line
			(start -0.12065 0.3048)
			(end -0.67945 0.3048)
			(stroke
				(width 0.1)
				(type default)
			)
			(layer "F.Fab")
		)
		(fp_line
			(start -0.67945 0.3048)
			(end -0.67945 -0.305054)
			(stroke
				(width 0.1)
				(type default)
			)
			(layer "F.Fab")
		)
		(pad "1" smd circle
			(at -0.40005 0 90)
			(size 0 0)
			(layers "F.Cu" "F.Mask" "F.Paste")
			(net "P12V_AUX")
		)
		(pad "2" smd circle
			(at 0.40005 0 90)
			(size 0 0)
			(layers "F.Cu" "F.Mask" "F.Paste")
			(net "GND")
		)
	)
	(footprint ""
		(layer "F.Cu")
		(at 120.36044 -426.075348 180)
		(property "Reference" "R2936"
			(at 0 0 180)
			(layer "F.SilkS")
			(hide yes)
			(effects
				(font
					(size 1.27 1.27)
				)
			)
		)
		(property "Value" ""
			(at 0 0 180)
			(layer "F.Fab")
			(effects
				(font
					(size 1.27 1.27)
				)
			)
		)
		(duplicate_pad_numbers_are_jumpers no)
		(fp_line
			(start 0.7874 0.4064)
			(end -0.7874 0.4064)
			(stroke
				(width 0.1524)
				(type default)
			)
			(layer "F.SilkS")
		)
		(fp_line
			(start 0.7874 -0.4064)
			(end 0.7874 0.4064)
			(stroke
				(width 0.1524)
				(type default)
			)
			(layer "F.SilkS")
		)
		(fp_line
			(start -0.7874 0.4064)
			(end -0.7874 -0.4064)
			(stroke
				(width 0.1524)
				(type default)
			)
			(layer "F.SilkS")
		)
		(fp_line
			(start -0.7874 -0.4064)
			(end 0.7874 -0.4064)
			(stroke
				(width 0.1524)
				(type default)
			)
			(layer "F.SilkS")
		)
		(fp_line
			(start 0.67945 0.3048)
			(end 0.120396 0.3048)
			(stroke
				(width 0.1)
				(type default)
			)
			(layer "F.Fab")
		)
		(fp_line
			(start 0.67945 -0.3048)
			(end 0.67945 0.3048)
			(stroke
				(width 0.1)
				(type default)
			)
			(layer "F.Fab")
		)
		(fp_line
			(start 0.12065 -0.2794)
			(end 0.12065 -0.3048)
			(stroke
				(width 0.1)
				(type default)
			)
			(layer "F.Fab")
		)
		(fp_line
			(start 0.12065 -0.3048)
			(end 0.67945 -0.3048)
			(stroke
				(width 0.1)
				(type default)
			)
			(layer "F.Fab")
		)
		(fp_line
			(start 0.120396 0.3048)
			(end 0.120396 0.2794)
			(stroke
				(width 0.1)
				(type default)
			)
			(layer "F.Fab")
		)
		(fp_line
			(start 0.120396 0.2794)
			(end -0.12065 0.2794)
			(stroke
				(width 0.1)
				(type default)
			)
			(layer "F.Fab")
		)
		(fp_line
			(start -0.12065 0.3048)
			(end -0.67945 0.3048)
			(stroke
				(width 0.1)
				(type default)
			)
			(layer "F.Fab")
		)
		(fp_line
			(start -0.12065 0.2794)
			(end -0.12065 0.3048)
			(stroke
				(width 0.1)
				(type default)
			)
			(layer "F.Fab")
		)
		(fp_line
			(start -0.12065 -0.2794)
			(end 0.12065 -0.2794)
			(stroke
				(width 0.1)
				(type default)
			)
			(layer "F.Fab")
		)
		(fp_line
			(start -0.12065 -0.305054)
			(end -0.12065 -0.2794)
			(stroke
				(width 0.1)
				(type default)
			)
			(layer "F.Fab")
		)
		(fp_line
			(start -0.67945 0.3048)
			(end -0.67945 -0.305054)
			(stroke
				(width 0.1)
				(type default)
			)
			(layer "F.Fab")
		)
		(fp_line
			(start -0.67945 -0.305054)
			(end -0.12065 -0.305054)
			(stroke
				(width 0.1)
				(type default)
			)
			(layer "F.Fab")
		)
		(pad "1" smd circle
			(at -0.40005 0 180)
			(size 0 0)
			(layers "F.Cu" "F.Mask" "F.Paste")
			(net "P3V3_AUX")
		)
		(pad "2" smd circle
			(at 0.40005 0 180)
			(size 0 0)
			(layers "F.Cu" "F.Mask" "F.Paste")
			(net "FM_GPU_PWR_EN_R")
		)
	)
	(footprint ""
		(layer "F.Cu")
		(at 74.2188 -35.347148 180)
		(property "Reference" "R3590"
			(at 0 0 180)
			(layer "F.SilkS")
			(hide yes)
			(effects
				(font
					(size 1.27 1.27)
				)
			)
		)
		(property "Value" ""
			(at 0 0 180)
			(layer "F.Fab")
			(effects
				(font
					(size 1.27 1.27)
				)
			)
		)
		(duplicate_pad_numbers_are_jumpers no)
		(fp_line
			(start 0.7874 0.4064)
			(end -0.7874 0.4064)
			(stroke
				(width 0.1524)
				(type default)
			)
			(layer "F.SilkS")
		)
		(fp_line
			(start 0.7874 -0.4064)
			(end 0.7874 0.4064)
			(stroke
				(width 0.1524)
				(type default)
			)
			(layer "F.SilkS")
		)
		(fp_line
			(start -0.7874 0.4064)
			(end -0.7874 -0.4064)
			(stroke
				(width 0.1524)
				(type default)
			)
			(layer "F.SilkS")
		)
		(fp_line
			(start -0.7874 -0.4064)
			(end 0.7874 -0.4064)
			(stroke
				(width 0.1524)
				(type default)
			)
			(layer "F.SilkS")
		)
		(fp_line
			(start 0.67945 0.3048)
			(end 0.120396 0.3048)
			(stroke
				(width 0.1)
				(type default)
			)
			(layer "F.Fab")
		)
		(fp_line
			(start 0.67945 -0.3048)
			(end 0.67945 0.3048)
			(stroke
				(width 0.1)
				(type default)
			)
			(layer "F.Fab")
		)
		(fp_line
			(start 0.12065 -0.2794)
			(end 0.12065 -0.3048)
			(stroke
				(width 0.1)
				(type default)
			)
			(layer "F.Fab")
		)
		(fp_line
			(start 0.12065 -0.3048)
			(end 0.67945 -0.3048)
			(stroke
				(width 0.1)
				(type default)
			)
			(layer "F.Fab")
		)
		(fp_line
			(start 0.120396 0.3048)
			(end 0.120396 0.2794)
			(stroke
				(width 0.1)
				(type default)
			)
			(layer "F.Fab")
		)
		(fp_line
			(start 0.120396 0.2794)
			(end -0.12065 0.2794)
			(stroke
				(width 0.1)
				(type default)
			)
			(layer "F.Fab")
		)
		(fp_line
			(start -0.12065 0.3048)
			(end -0.67945 0.3048)
			(stroke
				(width 0.1)
				(type default)
			)
			(layer "F.Fab")
		)
		(fp_line
			(start -0.12065 0.2794)
			(end -0.12065 0.3048)
			(stroke
				(width 0.1)
				(type default)
			)
			(layer "F.Fab")
		)
		(fp_line
			(start -0.12065 -0.2794)
			(end 0.12065 -0.2794)
			(stroke
				(width 0.1)
				(type default)
			)
			(layer "F.Fab")
		)
		(fp_line
			(start -0.12065 -0.305054)
			(end -0.12065 -0.2794)
			(stroke
				(width 0.1)
				(type default)
			)
			(layer "F.Fab")
		)
		(fp_line
			(start -0.67945 0.3048)
			(end -0.67945 -0.305054)
			(stroke
				(width 0.1)
				(type default)
			)
			(layer "F.Fab")
		)
		(fp_line
			(start -0.67945 -0.305054)
			(end -0.12065 -0.305054)
			(stroke
				(width 0.1)
				(type default)
			)
			(layer "F.Fab")
		)
		(pad "1" smd circle
			(at -0.40005 0 180)
			(size 0 0)
			(layers "F.Cu" "F.Mask" "F.Paste")
			(net "SMB_INA230_3V3AUX_SCL")
		)
		(pad "2" smd circle
			(at 0.40005 0 180)
			(size 0 0)
			(layers "F.Cu" "F.Mask" "F.Paste")
			(net "SMB_INA230_3_3V3AUX_SCL_R")
		)
	)
)
